(kicad_pcb
	(version 20260206)
	(generator "pcbnew")
	(generator_version "10.0")
	(general
		(thickness 1.6)
		(legacy_teardrops no)
	)
	(paper "A4")
	(title_block
		(title "Wiwynn_Tioga_Pass_MB.brd")
		(comment 1 "Tioga Pass / footprints 3887-3893 of 4770")
	)
	(layers
		(0 "F.Cu" signal "TOP")
		(4 "In1.Cu" signal "L2GND")
		(6 "In2.Cu" signal "L3")
		(8 "In3.Cu" signal "L4GND")
		(10 "In4.Cu" signal "L5")
		(12 "In5.Cu" signal "L6GND")
		(14 "In6.Cu" signal "L7VCC")
		(16 "In7.Cu" signal "L8VCC")
		(18 "In8.Cu" signal "L9GND")
		(20 "In9.Cu" signal "L10")
		(22 "In10.Cu" signal "L11GND")
		(24 "In11.Cu" signal "L12")
		(26 "In12.Cu" signal "L13GND")
		(2 "B.Cu" signal "BOTTOM")
		(9 "F.Adhes" user "F.Adhesive")
		(11 "B.Adhes" user "B.Adhesive")
		(13 "F.Paste" user "Package Geometry/Pastemask Top")
		(15 "B.Paste" user "Package Geometry/Pastemask Bottom")
		(5 "F.SilkS" user "Ref Des/Silkscreen Top")
		(7 "B.SilkS" user "Ref Des/Silkscreen Bottom")
		(1 "F.Mask" user "Board Geometry/Soldermask Top")
		(3 "B.Mask" user "Board Geometry/Soldermask Bottom")
		(17 "Dwgs.User" user "User.Drawings")
		(19 "Cmts.User" user "User.Comments")
		(21 "Eco1.User" user "User.Eco1")
		(23 "Eco2.User" user "User.Eco2")
		(25 "Edge.Cuts" user "Board Geometry/Outline")
		(27 "Margin" user)
		(31 "F.CrtYd" user "Package Geometry/Place Bound Top")
		(29 "B.CrtYd" user "Package Geometry/Place Bound Bottom")
		(35 "F.Fab" user "Ref Des/Assembly Top")
		(33 "B.Fab" user "Ref Des/Assembly Bottom")
	)
	(footprint ""
		(layer "B.Cu")
		(at 350.3168 -153.8732 180)
		(property "Reference" "CT43"
			(at 0.8382 -0.84963 180)
			(unlocked yes)
			(layer "B.SilkS")
			(effects
				(font
					(size 0.7874 0.5842)
					(thickness 0.1524)
				)
				(justify left mirror)
			)
		)
		(property "Value" ""
			(at 0 0 0)
			(layer "B.Fab")
			(effects
				(font
					(size 1.27 1.27)
				)
				(justify mirror)
			)
		)
		(duplicate_pad_numbers_are_jumpers no)
		(fp_poly
			(pts
				(xy -0.3048 -0.1016) (xy -0.3048 0.9906) (xy 0.3048 0.9906) (xy 0.3048 -0.1016)
			)
			(stroke
				(width 0)
				(type default)
			)
			(fill no)
			(layer "B.CrtYd")
		)
		(fp_line
			(start 0.3048 0.9906)
			(end -0.3048 0.9906)
			(stroke
				(width 0.1)
				(type default)
			)
			(layer "B.Fab")
		)
		(fp_line
			(start 0.3048 -0.1016)
			(end 0.3048 0.9906)
			(stroke
				(width 0.1)
				(type default)
			)
			(layer "B.Fab")
		)
		(fp_line
			(start -0.3048 0.9906)
			(end -0.3048 -0.1016)
			(stroke
				(width 0.1)
				(type default)
			)
			(layer "B.Fab")
		)
		(fp_line
			(start -0.3048 -0.1016)
			(end 0.3048 -0.1016)
			(stroke
				(width 0.1)
				(type default)
			)
			(layer "B.Fab")
		)
		(pad "1" smd rect
			(at 0 0)
			(size 0.508 0.508)
			(layers "B.Cu" "B.Mask" "B.Paste")
			(net "A_TSENSE_PVDDQ_DEF")
		)
		(pad "2" smd rect
			(at 0 0.889)
			(size 0.508 0.508)
			(layers "B.Cu" "B.Mask" "B.Paste")
			(net "GND")
		)
		(zone
			(layer "B.Cu")
			(hatch none 0.5)
			(connect_pads
				(clearance 0)
			)
			(min_thickness 0.25)
			(keepout
				(tracks not_allowed)
				(vias allowed)
				(pads allowed)
				(copperpour not_allowed)
				(footprints allowed)
			)
			(placement
				(enabled no)
				(sheetname "")
			)
			(fill
				(thermal_gap 0.5)
				(thermal_bridge_width 0.5)
				(island_removal_mode 0)
			)
			(polygon
				(pts
					(xy 350.0628 -154.5082) (xy 350.5708 -154.5082) (xy 350.5708 -154.1272) (xy 350.0628 -154.1272)
				)
			)
		)
		(zone
			(layer "B.Cu")
			(hatch none 0.5)
			(connect_pads
				(clearance 0)
			)
			(min_thickness 0.25)
			(keepout
				(tracks allowed)
				(vias not_allowed)
				(pads allowed)
				(copperpour not_allowed)
				(footprints allowed)
			)
			(placement
				(enabled no)
				(sheetname "")
			)
			(fill
				(thermal_gap 0.5)
				(thermal_bridge_width 0.5)
				(island_removal_mode 0)
			)
			(polygon
				(pts
					(xy 350.0628 -154.1272) (xy 350.5708 -154.1272) (xy 350.5708 -154.5082) (xy 350.0628 -154.5082)
				)
			)
		)
	)
	(footprint ""
		(layer "B.Cu")
		(at 344.678 -82.677 180)
		(property "Reference" "R3P25"
			(at 0 0 0)
			(layer "B.SilkS")
			(hide yes)
			(effects
				(font
					(size 1.27 1.27)
				)
				(justify mirror)
			)
		)
		(property "Value" ""
			(at 0 0 0)
			(layer "B.Fab")
			(effects
				(font
					(size 1.27 1.27)
				)
				(justify mirror)
			)
		)
		(duplicate_pad_numbers_are_jumpers no)
		(fp_poly
			(pts
				(xy 0.2794 -0.1016) (xy -0.2794 -0.1016) (xy -0.2794 0.9906) (xy 0.2794 0.9906)
			)
			(stroke
				(width 0)
				(type default)
			)
			(fill no)
			(layer "B.CrtYd")
		)
		(fp_line
			(start 0.2794 0.9906)
			(end -0.2794 0.9906)
			(stroke
				(width 0.1)
				(type default)
			)
			(layer "B.Fab")
		)
		(fp_line
			(start 0.2794 -0.1016)
			(end 0.2794 0.9906)
			(stroke
				(width 0.1)
				(type default)
			)
			(layer "B.Fab")
		)
		(fp_line
			(start -0.2794 0.9906)
			(end -0.2794 -0.1016)
			(stroke
				(width 0.1)
				(type default)
			)
			(layer "B.Fab")
		)
		(fp_line
			(start -0.2794 -0.1016)
			(end 0.2794 -0.1016)
			(stroke
				(width 0.1)
				(type default)
			)
			(layer "B.Fab")
		)
		(pad "1" smd rect
			(at 0 0)
			(size 0.508 0.508)
			(layers "B.Cu" "B.Mask" "B.Paste")
			(net "P3V3_STBY")
		)
		(pad "2" smd rect
			(at 0 0.889)
			(size 0.508 0.508)
			(layers "B.Cu" "B.Mask" "B.Paste")
			(net "PWRGD_PVCCIO_CPU0_R")
		)
		(zone
			(layer "B.Cu")
			(hatch none 0.5)
			(connect_pads
				(clearance 0)
			)
			(min_thickness 0.25)
			(keepout
				(tracks not_allowed)
				(vias allowed)
				(pads allowed)
				(copperpour not_allowed)
				(footprints allowed)
			)
			(placement
				(enabled no)
				(sheetname "")
			)
			(fill
				(thermal_gap 0.5)
				(thermal_bridge_width 0.5)
				(island_removal_mode 0)
			)
			(polygon
				(pts
					(xy 344.424 -83.312) (xy 344.932 -83.312) (xy 344.932 -82.931) (xy 344.424 -82.931)
				)
			)
		)
		(zone
			(layer "B.Cu")
			(hatch none 0.5)
			(connect_pads
				(clearance 0)
			)
			(min_thickness 0.25)
			(keepout
				(tracks allowed)
				(vias not_allowed)
				(pads allowed)
				(copperpour not_allowed)
				(footprints allowed)
			)
			(placement
				(enabled no)
				(sheetname "")
			)
			(fill
				(thermal_gap 0.5)
				(thermal_bridge_width 0.5)
				(island_removal_mode 0)
			)
			(polygon
				(pts
					(xy 344.424 -82.931) (xy 344.932 -82.931) (xy 344.932 -83.312) (xy 344.424 -83.312)
				)
			)
		)
	)
	(footprint ""
		(layer "B.Cu")
		(at 276.479 -68.58 90)
		(property "Reference" "R4P17"
			(at 0 0 90)
			(layer "B.SilkS")
			(hide yes)
			(effects
				(font
					(size 1.27 1.27)
				)
				(justify mirror)
			)
		)
		(property "Value" ""
			(at 0 0 90)
			(layer "B.Fab")
			(effects
				(font
					(size 1.27 1.27)
				)
				(justify mirror)
			)
		)
		(duplicate_pad_numbers_are_jumpers no)
		(fp_poly
			(pts
				(xy 0.2794 -0.1016) (xy -0.2794 -0.1016) (xy -0.2794 0.9906) (xy 0.2794 0.9906)
			)
			(stroke
				(width 0)
				(type default)
			)
			(fill no)
			(layer "B.CrtYd")
		)
		(fp_line
			(start 0.2794 -0.1016)
			(end 0.2794 0.9906)
			(stroke
				(width 0.1)
				(type default)
			)
			(layer "B.Fab")
		)
		(fp_line
			(start -0.2794 -0.1016)
			(end 0.2794 -0.1016)
			(stroke
				(width 0.1)
				(type default)
			)
			(layer "B.Fab")
		)
		(fp_line
			(start 0.2794 0.9906)
			(end -0.2794 0.9906)
			(stroke
				(width 0.1)
				(type default)
			)
			(layer "B.Fab")
		)
		(fp_line
			(start -0.2794 0.9906)
			(end -0.2794 -0.1016)
			(stroke
				(width 0.1)
				(type default)
			)
			(layer "B.Fab")
		)
		(pad "1" smd rect
			(at 0 0 270)
			(size 0.508 0.508)
			(layers "B.Cu" "B.Mask" "B.Paste")
			(net "H_CPU0_MEMABC_MEMHOT_G_N")
		)
		(pad "2" smd rect
			(at 0 0.889 270)
			(size 0.508 0.508)
			(layers "B.Cu" "B.Mask" "B.Paste")
			(net "PVCCIO_CPU0")
		)
		(zone
			(layer "B.Cu")
			(hatch none 0.5)
			(connect_pads
				(clearance 0)
			)
			(min_thickness 0.25)
			(keepout
				(tracks allowed)
				(vias not_allowed)
				(pads allowed)
				(copperpour not_allowed)
				(footprints allowed)
			)
			(placement
				(enabled no)
				(sheetname "")
			)
			(fill
				(thermal_gap 0.5)
				(thermal_bridge_width 0.5)
				(island_removal_mode 0)
			)
			(polygon
				(pts
					(xy 276.733 -68.834) (xy 276.733 -68.326) (xy 277.114 -68.326) (xy 277.114 -68.834)
				)
			)
		)
		(zone
			(layer "B.Cu")
			(hatch none 0.5)
			(connect_pads
				(clearance 0)
			)
			(min_thickness 0.25)
			(keepout
				(tracks not_allowed)
				(vias allowed)
				(pads allowed)
				(copperpour not_allowed)
				(footprints allowed)
			)
			(placement
				(enabled no)
				(sheetname "")
			)
			(fill
				(thermal_gap 0.5)
				(thermal_bridge_width 0.5)
				(island_removal_mode 0)
			)
			(polygon
				(pts
					(xy 277.114 -68.834) (xy 277.114 -68.326) (xy 276.733 -68.326) (xy 276.733 -68.834)
				)
			)
		)
	)
	(footprint ""
		(layer "B.Cu")
		(at 468.884 -127.635 180)
		(property "Reference" "R1M25"
			(at 0 0 0)
			(layer "B.SilkS")
			(hide yes)
			(effects
				(font
					(size 1.27 1.27)
				)
				(justify mirror)
			)
		)
		(property "Value" ""
			(at 0 0 0)
			(layer "B.Fab")
			(effects
				(font
					(size 1.27 1.27)
				)
				(justify mirror)
			)
		)
		(duplicate_pad_numbers_are_jumpers no)
		(fp_poly
			(pts
				(xy 0.2794 -0.1016) (xy -0.2794 -0.1016) (xy -0.2794 0.9906) (xy 0.2794 0.9906)
			)
			(stroke
				(width 0)
				(type default)
			)
			(fill no)
			(layer "B.CrtYd")
		)
		(fp_line
			(start 0.2794 0.9906)
			(end -0.2794 0.9906)
			(stroke
				(width 0.1)
				(type default)
			)
			(layer "B.Fab")
		)
		(fp_line
			(start 0.2794 -0.1016)
			(end 0.2794 0.9906)
			(stroke
				(width 0.1)
				(type default)
			)
			(layer "B.Fab")
		)
		(fp_line
			(start -0.2794 0.9906)
			(end -0.2794 -0.1016)
			(stroke
				(width 0.1)
				(type default)
			)
			(layer "B.Fab")
		)
		(fp_line
			(start -0.2794 -0.1016)
			(end 0.2794 -0.1016)
			(stroke
				(width 0.1)
				(type default)
			)
			(layer "B.Fab")
		)
		(pad "1" smd rect
			(at 0 0)
			(size 0.508 0.508)
			(layers "B.Cu" "B.Mask" "B.Paste")
			(net "FM_USB_P0_EN_R_N")
		)
		(pad "2" smd rect
			(at 0 0.889)
			(size 0.508 0.508)
			(layers "B.Cu" "B.Mask" "B.Paste")
			(net "GND")
		)
		(zone
			(layer "B.Cu")
			(hatch none 0.5)
			(connect_pads
				(clearance 0)
			)
			(min_thickness 0.25)
			(keepout
				(tracks not_allowed)
				(vias allowed)
				(pads allowed)
				(copperpour not_allowed)
				(footprints allowed)
			)
			(placement
				(enabled no)
				(sheetname "")
			)
			(fill
				(thermal_gap 0.5)
				(thermal_bridge_width 0.5)
				(island_removal_mode 0)
			)
			(polygon
				(pts
					(xy 468.63 -128.27) (xy 469.138 -128.27) (xy 469.138 -127.889) (xy 468.63 -127.889)
				)
			)
		)
		(zone
			(layer "B.Cu")
			(hatch none 0.5)
			(connect_pads
				(clearance 0)
			)
			(min_thickness 0.25)
			(keepout
				(tracks allowed)
				(vias not_allowed)
				(pads allowed)
				(copperpour not_allowed)
				(footprints allowed)
			)
			(placement
				(enabled no)
				(sheetname "")
			)
			(fill
				(thermal_gap 0.5)
				(thermal_bridge_width 0.5)
				(island_removal_mode 0)
			)
			(polygon
				(pts
					(xy 468.63 -127.889) (xy 469.138 -127.889) (xy 469.138 -128.27) (xy 468.63 -128.27)
				)
			)
		)
	)
	(footprint ""
		(layer "B.Cu")
		(at 104.5591 -8.1534 90)
		(property "Reference" "C8U2"
			(at -1.848866 0.752348 90)
			(unlocked yes)
			(layer "B.SilkS")
			(effects
				(font
					(size 1.27 0.9652)
					(thickness 0.1524)
				)
				(justify mirror)
			)
		)
		(property "Value" ""
			(at 0 0 90)
			(layer "B.Fab")
			(effects
				(font
					(size 1.27 1.27)
				)
				(justify mirror)
			)
		)
		(duplicate_pad_numbers_are_jumpers no)
		(fp_rect
			(start 0.500126 1.598422)
			(end -0.500126 -0.201422)
			(stroke
				(width 0)
				(type default)
			)
			(fill no)
			(layer "B.CrtYd")
		)
		(fp_line
			(start 0.500126 -0.201422)
			(end -0.500126 -0.201422)
			(stroke
				(width 0.1)
				(type default)
			)
			(layer "B.Fab")
		)
		(fp_line
			(start -0.500126 -0.201422)
			(end -0.500126 1.598422)
			(stroke
				(width 0.1)
				(type default)
			)
			(layer "B.Fab")
		)
		(fp_line
			(start 0.500126 1.598422)
			(end 0.500126 -0.201422)
			(stroke
				(width 0.1)
				(type default)
			)
			(layer "B.Fab")
		)
		(fp_line
			(start -0.500126 1.598422)
			(end 0.500126 1.598422)
			(stroke
				(width 0.1)
				(type default)
			)
			(layer "B.Fab")
		)
		(pad "1" smd rect
			(at 0 0)
			(size 0.889 0.9906)
			(layers "B.Cu" "B.Mask" "B.Paste")
			(net "PVDDQ_GHJ")
		)
		(pad "2" smd rect
			(at 0 1.397)
			(size 0.889 0.9906)
			(layers "B.Cu" "B.Mask" "B.Paste")
			(net "GND")
		)
		(zone
			(layer "B.Cu")
			(hatch none 0.5)
			(connect_pads
				(clearance 0)
			)
			(min_thickness 0.25)
			(keepout
				(tracks allowed)
				(vias not_allowed)
				(pads allowed)
				(copperpour not_allowed)
				(footprints allowed)
			)
			(placement
				(enabled no)
				(sheetname "")
			)
			(fill
				(thermal_gap 0.5)
				(thermal_bridge_width 0.5)
				(island_removal_mode 0)
			)
			(polygon
				(pts
					(xy 105.5116 -8.6487) (xy 105.0036 -8.6487) (xy 105.0036 -7.6581) (xy 105.5116 -7.6581)
				)
			)
		)
		(zone
			(layer "B.Cu")
			(hatch none 0.5)
			(connect_pads
				(clearance 0)
			)
			(min_thickness 0.25)
			(keepout
				(tracks not_allowed)
				(vias allowed)
				(pads allowed)
				(copperpour not_allowed)
				(footprints allowed)
			)
			(placement
				(enabled no)
				(sheetname "")
			)
			(fill
				(thermal_gap 0.5)
				(thermal_bridge_width 0.5)
				(island_removal_mode 0)
			)
			(polygon
				(pts
					(xy 105.5116 -8.6487) (xy 105.0036 -8.6487) (xy 105.0036 -7.6581) (xy 105.5116 -7.6581)
				)
			)
		)
	)
	(footprint ""
		(layer "B.Cu")
		(at 499.62816 -128.52654 -90)
		(property "Reference" "U1M6"
			(at -1.6383 -1.23317 270)
			(unlocked yes)
			(layer "B.SilkS")
			(effects
				(font
					(size 0.7874 0.5842)
					(thickness 0.1524)
				)
				(justify left mirror)
			)
		)
		(property "Value" ""
			(at 0 0 90)
			(layer "B.Fab")
			(effects
				(font
					(size 1.27 1.27)
				)
				(justify mirror)
			)
		)
		(duplicate_pad_numbers_are_jumpers no)
		(fp_circle
			(center 0.4699 -0.8382)
			(end 0.4699 -0.9652)
			(stroke
				(width 0.254)
				(type default)
			)
			(fill no)
			(layer "B.SilkS")
		)
		(fp_poly
			(pts
				(xy -0.21463 -0.450088) (xy -1.56337 -0.450088) (xy -1.56337 1.75006) (xy -0.21463 1.75006)
			)
			(stroke
				(width 0)
				(type default)
			)
			(fill no)
			(layer "B.CrtYd")
		)
		(fp_line
			(start -1.56337 1.75006)
			(end -0.21463 1.75006)
			(stroke
				(width 0.1)
				(type default)
			)
			(layer "B.Fab")
		)
		(fp_line
			(start -0.21463 1.75006)
			(end -0.21463 -0.450088)
			(stroke
				(width 0.1)
				(type default)
			)
			(layer "B.Fab")
		)
		(fp_line
			(start -1.56337 -0.450088)
			(end -1.56337 1.75006)
			(stroke
				(width 0.1)
				(type default)
			)
			(layer "B.Fab")
		)
		(fp_line
			(start -0.21463 -0.450088)
			(end -1.56337 -0.450088)
			(stroke
				(width 0.1)
				(type default)
			)
			(layer "B.Fab")
		)
		(fp_circle
			(center 0.4699 -0.8382)
			(end 0.4699 -0.9652)
			(stroke
				(width 0.254)
				(type default)
			)
			(fill no)
			(layer "B.Fab")
		)
		(pad "1" smd rect
			(at 0 0 90)
			(size 1.016 0.381)
			(layers "B.Cu" "B.Mask" "B.Paste")
			(net "FM_CPU0_AND_CPU1_MCP_PRES")
		)
		(pad "2" smd rect
			(at 0 0.649986 90)
			(size 1.016 0.381)
			(layers "B.Cu" "B.Mask" "B.Paste")
			(net "JTAG_MCP_CPU0_TDO")
		)
		(pad "3" smd rect
			(at 0 1.299972 90)
			(size 1.016 0.381)
			(layers "B.Cu" "B.Mask" "B.Paste")
			(net "GND")
		)
		(pad "4" smd rect
			(at -1.778 1.299972 90)
			(size 1.016 0.381)
			(layers "B.Cu" "B.Mask" "B.Paste")
			(net "JTAG_MCP_CPU1_TDI")
		)
		(pad "5" smd rect
			(at -1.778 0 90)
			(size 1.016 0.381)
			(layers "B.Cu" "B.Mask" "B.Paste")
			(net "P3V3_STBY")
		)
	)
	(footprint ""
		(layer "B.Cu")
		(at 88.392 -17.7546 90)
		(property "Reference" "C8T7"
			(at -1.848866 0.752348 90)
			(unlocked yes)
			(layer "B.SilkS")
			(effects
				(font
					(size 1.27 0.9652)
					(thickness 0.1524)
				)
				(justify mirror)
			)
		)
		(property "Value" ""
			(at 0 0 90)
			(layer "B.Fab")
			(effects
				(font
					(size 1.27 1.27)
				)
				(justify mirror)
			)
		)
		(duplicate_pad_numbers_are_jumpers no)
		(fp_rect
			(start 0.500126 1.598422)
			(end -0.500126 -0.201422)
			(stroke
				(width 0)
				(type default)
			)
			(fill no)
			(layer "B.CrtYd")
		)
		(fp_line
			(start 0.500126 -0.201422)
			(end -0.500126 -0.201422)
			(stroke
				(width 0.1)
				(type default)
			)
			(layer "B.Fab")
		)
		(fp_line
			(start -0.500126 -0.201422)
			(end -0.500126 1.598422)
			(stroke
				(width 0.1)
				(type default)
			)
			(layer "B.Fab")
		)
		(fp_line
			(start 0.500126 1.598422)
			(end 0.500126 -0.201422)
			(stroke
				(width 0.1)
				(type default)
			)
			(layer "B.Fab")
		)
		(fp_line
			(start -0.500126 1.598422)
			(end 0.500126 1.598422)
			(stroke
				(width 0.1)
				(type default)
			)
			(layer "B.Fab")
		)
		(pad "1" smd rect
			(at 0 0)
			(size 0.889 0.9906)
			(layers "B.Cu" "B.Mask" "B.Paste")
			(net "PVDDQ_GHJ")
		)
		(pad "2" smd rect
			(at 0 1.397)
			(size 0.889 0.9906)
			(layers "B.Cu" "B.Mask" "B.Paste")
			(net "GND")
		)
		(zone
			(layer "B.Cu")
			(hatch none 0.5)
			(connect_pads
				(clearance 0)
			)
			(min_thickness 0.25)
			(keepout
				(tracks allowed)
				(vias not_allowed)
				(pads allowed)
				(copperpour not_allowed)
				(footprints allowed)
			)
			(placement
				(enabled no)
				(sheetname "")
			)
			(fill
				(thermal_gap 0.5)
				(thermal_bridge_width 0.5)
				(island_removal_mode 0)
			)
			(polygon
				(pts
					(xy 89.3445 -18.2499) (xy 88.8365 -18.2499) (xy 88.8365 -17.2593) (xy 89.3445 -17.2593)
				)
			)
		)
		(zone
			(layer "B.Cu")
			(hatch none 0.5)
			(connect_pads
				(clearance 0)
			)
			(min_thickness 0.25)
			(keepout
				(tracks not_allowed)
				(vias allowed)
				(pads allowed)
				(copperpour not_allowed)
				(footprints allowed)
			)
			(placement
				(enabled no)
				(sheetname "")
			)
			(fill
				(thermal_gap 0.5)
				(thermal_bridge_width 0.5)
				(island_removal_mode 0)
			)
			(polygon
				(pts
					(xy 89.3445 -18.2499) (xy 88.8365 -18.2499) (xy 88.8365 -17.2593) (xy 89.3445 -17.2593)
				)
			)
		)
	)
)
